(kicad_pcb
	(version 20260206)
	(generator "pcbnew")
	(generator_version "10.0")
	(general
		(thickness 1.6)
		(legacy_teardrops no)
	)
	(paper "A4")
	(title_block
		(title "v1-chassis-manager — T6M_CM_d_v01_1031_1645.brd")
		(comment 1 "Open CloudServer (Microsoft) / footprints 2072-2081 of 2512")
	)
	(layers
		(0 "F.Cu" signal "TOP")
		(4 "In1.Cu" signal "GND1")
		(6 "In2.Cu" signal "IN1")
		(8 "In3.Cu" signal "VCC1")
		(10 "In4.Cu" signal "VCC2")
		(12 "In5.Cu" signal "GND2")
		(14 "In6.Cu" signal "IN2")
		(16 "In7.Cu" signal "IN3")
		(18 "In8.Cu" signal "GND3")
		(2 "B.Cu" signal "BOTTOM")
		(9 "F.Adhes" user "F.Adhesive")
		(11 "B.Adhes" user "B.Adhesive")
		(13 "F.Paste" user "Package Geometry/Pastemask Top")
		(15 "B.Paste" user "Package Geometry/Pastemask Bottom")
		(5 "F.SilkS" user "Ref Des/Silkscreen Top")
		(7 "B.SilkS" user "Ref Des/Silkscreen Bottom")
		(1 "F.Mask" user "Board Geometry/Soldermask Top")
		(3 "B.Mask" user "Board Geometry/Soldermask Bottom")
		(17 "Dwgs.User" user "User.Drawings")
		(19 "Cmts.User" user "User.Comments")
		(21 "Eco1.User" user "User.Eco1")
		(23 "Eco2.User" user "User.Eco2")
		(25 "Edge.Cuts" user "Board Geometry/Outline")
		(27 "Margin" user)
		(31 "F.CrtYd" user "Package Geometry/Place Bound Top")
		(29 "B.CrtYd" user "Package Geometry/Place Bound Bottom")
		(35 "F.Fab" user "Ref Des/Assembly Top")
		(33 "B.Fab" user "Ref Des/Assembly Bottom")
	)
	(footprint ""
		(layer "B.Cu")
		(at 37.48786 -164.561012 -90)
		(property "Reference" ""
			(at 0 0 90)
			(layer "B.SilkS")
			(hide yes)
			(effects
				(font
					(size 1.27 1.27)
				)
				(justify mirror)
			)
		)
		(property "Value" ""
			(at 0 0 90)
			(layer "B.Fab")
			(effects
				(font
					(size 1.27 1.27)
				)
				(justify mirror)
			)
		)
		(duplicate_pad_numbers_are_jumpers no)
		(fp_poly
			(pts
				(arc
					(start 0 -1.4986)
					(mid 0 1.4986)
					(end 0 -1.4986)
				)
			)
			(stroke
				(width 0)
				(type default)
			)
			(fill no)
			(layer "B.CrtYd")
		)
		(pad "1" smd circle
			(at 0 0 90)
			(size 0.9906 0.9906)
			(layers "B.Cu" "B.Mask" "B.Paste")
			(net "Net_36")
		)
		(zone
			(layer "B.Cu")
			(hatch none 0.5)
			(connect_pads
				(clearance 0)
			)
			(min_thickness 0.25)
			(keepout
				(tracks not_allowed)
				(vias allowed)
				(pads allowed)
				(copperpour not_allowed)
				(footprints allowed)
			)
			(placement
				(enabled no)
				(sheetname "")
			)
			(fill
				(thermal_gap 0.5)
				(thermal_bridge_width 0.5)
				(island_removal_mode 0)
			)
			(polygon
				(pts
					(arc
						(start 39.11346 -164.561012)
						(mid 35.86226 -164.561012)
						(end 39.11346 -164.561012)
					)
				)
			)
		)
	)
	(footprint ""
		(layer "B.Cu")
		(at 115.30076 -188.126624 -90)
		(property "Reference" "C721"
			(at -4.080256 -0.700786 270)
			(unlocked yes)
			(layer "B.SilkS")
			(effects
				(font
					(size 0.7874 0.5842)
					(thickness 0.1524)
				)
				(justify left mirror)
			)
		)
		(property "Value" ""
			(at 0 0 90)
			(layer "B.Fab")
			(effects
				(font
					(size 1.27 1.27)
				)
				(justify mirror)
			)
		)
		(duplicate_pad_numbers_are_jumpers no)
		(fp_line
			(start -0.7874 0.4064)
			(end 0.7874 0.4064)
			(stroke
				(width 0.1524)
				(type default)
			)
			(layer "B.SilkS")
		)
		(fp_line
			(start 0.7874 0.4064)
			(end 0.7874 -0.4064)
			(stroke
				(width 0.1524)
				(type default)
			)
			(layer "B.SilkS")
		)
		(fp_line
			(start 0 0.381)
			(end 0 -0.381)
			(stroke
				(width 0.1524)
				(type default)
			)
			(layer "B.SilkS")
		)
		(fp_line
			(start -0.7874 -0.4064)
			(end -0.7874 0.4064)
			(stroke
				(width 0.1524)
				(type default)
			)
			(layer "B.SilkS")
		)
		(fp_line
			(start 0.7874 -0.4064)
			(end -0.7874 -0.4064)
			(stroke
				(width 0.1524)
				(type default)
			)
			(layer "B.SilkS")
		)
		(fp_poly
			(pts
				(xy 0.5334 0.254) (xy 0.635 0.254) (xy 0.635 0.2286) (xy 0.635 -0.254) (xy 0.5334 -0.254) (xy 0.5334 -0.2794)
				(xy -0.5334 -0.2794) (xy -0.5334 -0.254) (xy -0.635 -0.254) (xy -0.635 0.254) (xy -0.5334 0.254)
				(xy -0.5334 0.2794) (xy 0.508 0.2794) (xy 0.5334 0.2794)
			)
			(stroke
				(width 0)
				(type default)
			)
			(fill no)
			(layer "B.CrtYd")
		)
		(pad "1" smd rect
			(at -0.40005 0 90)
			(size 0.4572 0.508)
			(layers "B.Cu" "B.Mask" "B.Paste")
			(net "UART_T7_NODE1_TXD_R")
		)
		(pad "2" smd rect
			(at 0.40005 0 90)
			(size 0.4572 0.508)
			(layers "B.Cu" "B.Mask" "B.Paste")
			(net "GND")
		)
	)
	(footprint ""
		(layer "B.Cu")
		(at 88.77935 -73.685654)
		(property "Reference" "R161"
			(at -1.91516 9.834118 0)
			(unlocked yes)
			(layer "B.SilkS")
			(effects
				(font
					(size 0.7874 0.5842)
					(thickness 0.1524)
				)
				(justify left mirror)
			)
		)
		(property "Value" ""
			(at 0 0 0)
			(layer "B.Fab")
			(effects
				(font
					(size 1.27 1.27)
				)
				(justify mirror)
			)
		)
		(duplicate_pad_numbers_are_jumpers no)
		(fp_line
			(start -0.7874 -0.4064)
			(end -0.7874 0.4064)
			(stroke
				(width 0.1524)
				(type default)
			)
			(layer "B.SilkS")
		)
		(fp_line
			(start -0.7874 0.4064)
			(end 0.7874 0.4064)
			(stroke
				(width 0.1524)
				(type default)
			)
			(layer "B.SilkS")
		)
		(fp_line
			(start 0.7874 -0.4064)
			(end -0.7874 -0.4064)
			(stroke
				(width 0.1524)
				(type default)
			)
			(layer "B.SilkS")
		)
		(fp_line
			(start 0.7874 0.4064)
			(end 0.7874 -0.4064)
			(stroke
				(width 0.1524)
				(type default)
			)
			(layer "B.SilkS")
		)
		(fp_poly
			(pts
				(xy 0.508 0.2794) (xy 0.508 0.2286) (xy 0.635 0.2286) (xy 0.635 -0.254) (xy 0.5334 -0.254) (xy 0.5334 -0.2794)
				(xy -0.5334 -0.2794) (xy -0.5334 -0.254) (xy -0.635 -0.254) (xy -0.635 0.254) (xy -0.5334 0.254)
				(xy -0.5334 0.2794)
			)
			(stroke
				(width 0)
				(type default)
			)
			(fill no)
			(layer "B.CrtYd")
		)
		(pad "1" smd rect
			(at -0.40005 0 180)
			(size 0.4572 0.508)
			(layers "B.Cu" "B.Mask" "B.Paste")
			(net "GND")
		)
		(pad "2" smd rect
			(at 0.40005 0 180)
			(size 0.4572 0.508)
			(layers "B.Cu" "B.Mask" "B.Paste")
			(net "PD_CPU_NODE1_SPD_EN_L")
		)
	)
	(footprint ""
		(layer "B.Cu")
		(at 26.364184 -163.66363)
		(property "Reference" "C510"
			(at 0.4826 2.188972 0)
			(unlocked yes)
			(layer "B.SilkS")
			(effects
				(font
					(size 0.7874 0.5842)
					(thickness 0.1524)
				)
				(justify left mirror)
			)
		)
		(property "Value" ""
			(at 0 0 0)
			(layer "B.Fab")
			(effects
				(font
					(size 1.27 1.27)
				)
				(justify mirror)
			)
		)
		(duplicate_pad_numbers_are_jumpers no)
		(fp_line
			(start -0.7874 -0.4064)
			(end -0.7874 0.4064)
			(stroke
				(width 0.1524)
				(type default)
			)
			(layer "B.SilkS")
		)
		(fp_line
			(start -0.7874 0.4064)
			(end 0.7874 0.4064)
			(stroke
				(width 0.1524)
				(type default)
			)
			(layer "B.SilkS")
		)
		(fp_line
			(start 0 0.381)
			(end 0 -0.381)
			(stroke
				(width 0.1524)
				(type default)
			)
			(layer "B.SilkS")
		)
		(fp_line
			(start 0.7874 -0.4064)
			(end -0.7874 -0.4064)
			(stroke
				(width 0.1524)
				(type default)
			)
			(layer "B.SilkS")
		)
		(fp_line
			(start 0.7874 0.4064)
			(end 0.7874 -0.4064)
			(stroke
				(width 0.1524)
				(type default)
			)
			(layer "B.SilkS")
		)
		(fp_poly
			(pts
				(xy 0.5334 0.254) (xy 0.635 0.254) (xy 0.635 0.2286) (xy 0.635 -0.254) (xy 0.5334 -0.254) (xy 0.5334 -0.2794)
				(xy -0.5334 -0.2794) (xy -0.5334 -0.254) (xy -0.635 -0.254) (xy -0.635 0.254) (xy -0.5334 0.254)
				(xy -0.5334 0.2794) (xy 0.508 0.2794) (xy 0.5334 0.2794)
			)
			(stroke
				(width 0)
				(type default)
			)
			(fill no)
			(layer "B.CrtYd")
		)
		(pad "1" smd rect
			(at -0.40005 0 180)
			(size 0.4572 0.508)
			(layers "B.Cu" "B.Mask" "B.Paste")
			(net "P1V9_LAN1")
		)
		(pad "2" smd rect
			(at 0.40005 0 180)
			(size 0.4572 0.508)
			(layers "B.Cu" "B.Mask" "B.Paste")
			(net "GND")
		)
	)
	(footprint ""
		(layer "B.Cu")
		(at 153.90876 -184.951624 90)
		(property "Reference" "R888"
			(at 4.281424 -2.403602 270)
			(unlocked yes)
			(layer "B.SilkS")
			(effects
				(font
					(size 0.7874 0.5842)
					(thickness 0.1524)
				)
				(justify left mirror)
			)
		)
		(property "Value" ""
			(at 0 0 90)
			(layer "B.Fab")
			(effects
				(font
					(size 1.27 1.27)
				)
				(justify mirror)
			)
		)
		(duplicate_pad_numbers_are_jumpers no)
		(fp_line
			(start 0.7874 -0.4064)
			(end -0.7874 -0.4064)
			(stroke
				(width 0.1524)
				(type default)
			)
			(layer "B.SilkS")
		)
		(fp_line
			(start -0.7874 -0.4064)
			(end -0.7874 0.4064)
			(stroke
				(width 0.1524)
				(type default)
			)
			(layer "B.SilkS")
		)
		(fp_line
			(start 0.7874 0.4064)
			(end 0.7874 -0.4064)
			(stroke
				(width 0.1524)
				(type default)
			)
			(layer "B.SilkS")
		)
		(fp_line
			(start -0.7874 0.4064)
			(end 0.7874 0.4064)
			(stroke
				(width 0.1524)
				(type default)
			)
			(layer "B.SilkS")
		)
		(fp_poly
			(pts
				(xy 0.508 0.2794) (xy 0.508 0.2286) (xy 0.635 0.2286) (xy 0.635 -0.254) (xy 0.5334 -0.254) (xy 0.5334 -0.2794)
				(xy -0.5334 -0.2794) (xy -0.5334 -0.254) (xy -0.635 -0.254) (xy -0.635 0.254) (xy -0.5334 0.254)
				(xy -0.5334 0.2794)
			)
			(stroke
				(width 0)
				(type default)
			)
			(fill no)
			(layer "B.CrtYd")
		)
		(pad "1" smd rect
			(at -0.40005 0 270)
			(size 0.4572 0.508)
			(layers "B.Cu" "B.Mask" "B.Paste")
			(net "T11_NODE2_EN")
		)
		(pad "2" smd rect
			(at 0.40005 0 270)
			(size 0.4572 0.508)
			(layers "B.Cu" "B.Mask" "B.Paste")
			(net "T11_NODE2_EN_R")
		)
	)
	(footprint ""
		(layer "B.Cu")
		(at 53.072538 -88.040718 90)
		(property "Reference" "C92"
			(at 2.385822 -1.412748 270)
			(unlocked yes)
			(layer "B.SilkS")
			(effects
				(font
					(size 0.7874 0.5842)
					(thickness 0.1524)
				)
				(justify mirror)
			)
		)
		(property "Value" ""
			(at 0 0 90)
			(layer "B.Fab")
			(effects
				(font
					(size 1.27 1.27)
				)
				(justify mirror)
			)
		)
		(duplicate_pad_numbers_are_jumpers no)
		(fp_line
			(start 1.2954 -0.5842)
			(end -1.2954 -0.5842)
			(stroke
				(width 0.1524)
				(type default)
			)
			(layer "B.SilkS")
		)
		(fp_line
			(start 0 -0.5842)
			(end 0 0.5842)
			(stroke
				(width 0.1524)
				(type default)
			)
			(layer "B.SilkS")
		)
		(fp_line
			(start -1.2954 -0.5842)
			(end -1.2954 0.5842)
			(stroke
				(width 0.1524)
				(type default)
			)
			(layer "B.SilkS")
		)
		(fp_line
			(start 1.2954 0.5842)
			(end 1.2954 -0.5842)
			(stroke
				(width 0.1524)
				(type default)
			)
			(layer "B.SilkS")
		)
		(fp_line
			(start -1.2954 0.5842)
			(end 1.2954 0.5842)
			(stroke
				(width 0.1524)
				(type default)
			)
			(layer "B.SilkS")
		)
		(fp_poly
			(pts
				(xy -0.8636 -0.4572) (xy -0.8636 -0.3556) (xy -1.143 -0.3556) (xy -1.143 0.3556) (xy -0.8636 0.3556)
				(xy -0.8636 0.4572) (xy 0.8636 0.4572) (xy 0.8636 0.3556) (xy 1.143 0.3556) (xy 1.143 -0.3556) (xy 0.8636 -0.3556)
				(xy 0.8636 -0.4572)
			)
			(stroke
				(width 0)
				(type default)
			)
			(fill no)
			(layer "B.CrtYd")
		)
		(fp_line
			(start 0.884936 -0.504952)
			(end -0.884936 -0.504952)
			(stroke
				(width 0.1)
				(type default)
			)
			(layer "B.Fab")
		)
		(fp_line
			(start -0.884936 -0.504952)
			(end -0.884936 0.504952)
			(stroke
				(width 0.1)
				(type default)
			)
			(layer "B.Fab")
		)
		(fp_line
			(start 0.884936 0.504952)
			(end 0.884936 -0.504952)
			(stroke
				(width 0.1)
				(type default)
			)
			(layer "B.Fab")
		)
		(fp_line
			(start -0.884936 0.504952)
			(end 0.884936 0.504952)
			(stroke
				(width 0.1)
				(type default)
			)
			(layer "B.Fab")
		)
		(pad "1" smd rect
			(at -0.7366 0 180)
			(size 0.7112 0.8128)
			(layers "B.Cu" "B.Mask" "B.Paste")
			(net "P1V8_NODE1")
		)
		(pad "2" smd rect
			(at 0.7366 0 180)
			(size 0.7112 0.8128)
			(layers "B.Cu" "B.Mask" "B.Paste")
			(net "GND")
		)
	)
	(footprint ""
		(layer "B.Cu")
		(at 129.600452 -119.055642)
		(property "Reference" "C7"
			(at 2.577338 0.113284 0)
			(unlocked yes)
			(layer "B.SilkS")
			(effects
				(font
					(size 0.7874 0.5842)
					(thickness 0.1524)
				)
				(justify left mirror)
			)
		)
		(property "Value" ""
			(at 0 0 0)
			(layer "B.Fab")
			(effects
				(font
					(size 1.27 1.27)
				)
				(justify mirror)
			)
		)
		(duplicate_pad_numbers_are_jumpers no)
		(fp_line
			(start -0.7874 -0.4064)
			(end -0.7874 0.4064)
			(stroke
				(width 0.1524)
				(type default)
			)
			(layer "B.SilkS")
		)
		(fp_line
			(start -0.7874 0.4064)
			(end 0.7874 0.4064)
			(stroke
				(width 0.1524)
				(type default)
			)
			(layer "B.SilkS")
		)
		(fp_line
			(start 0 0.381)
			(end 0 -0.381)
			(stroke
				(width 0.1524)
				(type default)
			)
			(layer "B.SilkS")
		)
		(fp_line
			(start 0.7874 -0.4064)
			(end -0.7874 -0.4064)
			(stroke
				(width 0.1524)
				(type default)
			)
			(layer "B.SilkS")
		)
		(fp_line
			(start 0.7874 0.4064)
			(end 0.7874 -0.4064)
			(stroke
				(width 0.1524)
				(type default)
			)
			(layer "B.SilkS")
		)
		(fp_poly
			(pts
				(xy 0.5334 0.254) (xy 0.635 0.254) (xy 0.635 0.2286) (xy 0.635 -0.254) (xy 0.5334 -0.254) (xy 0.5334 -0.2794)
				(xy -0.5334 -0.2794) (xy -0.5334 -0.254) (xy -0.635 -0.254) (xy -0.635 0.254) (xy -0.5334 0.254)
				(xy -0.5334 0.2794) (xy 0.508 0.2794) (xy 0.5334 0.2794)
			)
			(stroke
				(width 0)
				(type default)
			)
			(fill no)
			(layer "B.CrtYd")
		)
		(pad "1" smd rect
			(at -0.40005 0 180)
			(size 0.4572 0.508)
			(layers "B.Cu" "B.Mask" "B.Paste")
			(net "P1V5_CLK_NODE1")
		)
		(pad "2" smd rect
			(at 0.40005 0 180)
			(size 0.4572 0.508)
			(layers "B.Cu" "B.Mask" "B.Paste")
			(net "GND")
		)
	)
	(footprint ""
		(layer "B.Cu")
		(at 58.53176 -188.126624 -90)
		(property "Reference" "C685"
			(at -4.276598 -0.118364 270)
			(unlocked yes)
			(layer "B.SilkS")
			(effects
				(font
					(size 0.7874 0.5842)
					(thickness 0.1524)
				)
				(justify left mirror)
			)
		)
		(property "Value" ""
			(at 0 0 90)
			(layer "B.Fab")
			(effects
				(font
					(size 1.27 1.27)
				)
				(justify mirror)
			)
		)
		(duplicate_pad_numbers_are_jumpers no)
		(fp_line
			(start -0.7874 0.4064)
			(end 0.7874 0.4064)
			(stroke
				(width 0.1524)
				(type default)
			)
			(layer "B.SilkS")
		)
		(fp_line
			(start 0.7874 0.4064)
			(end 0.7874 -0.4064)
			(stroke
				(width 0.1524)
				(type default)
			)
			(layer "B.SilkS")
		)
		(fp_line
			(start 0 0.381)
			(end 0 -0.381)
			(stroke
				(width 0.1524)
				(type default)
			)
			(layer "B.SilkS")
		)
		(fp_line
			(start -0.7874 -0.4064)
			(end -0.7874 0.4064)
			(stroke
				(width 0.1524)
				(type default)
			)
			(layer "B.SilkS")
		)
		(fp_line
			(start 0.7874 -0.4064)
			(end -0.7874 -0.4064)
			(stroke
				(width 0.1524)
				(type default)
			)
			(layer "B.SilkS")
		)
		(fp_poly
			(pts
				(xy 0.5334 0.254) (xy 0.635 0.254) (xy 0.635 0.2286) (xy 0.635 -0.254) (xy 0.5334 -0.254) (xy 0.5334 -0.2794)
				(xy -0.5334 -0.2794) (xy -0.5334 -0.254) (xy -0.635 -0.254) (xy -0.635 0.254) (xy -0.5334 0.254)
				(xy -0.5334 0.2794) (xy 0.508 0.2794) (xy 0.5334 0.2794)
			)
			(stroke
				(width 0)
				(type default)
			)
			(fill no)
			(layer "B.CrtYd")
		)
		(pad "1" smd rect
			(at -0.40005 0 90)
			(size 0.4572 0.508)
			(layers "B.Cu" "B.Mask" "B.Paste")
			(net "UART_T1_NODE3_TXD_R")
		)
		(pad "2" smd rect
			(at 0.40005 0 90)
			(size 0.4572 0.508)
			(layers "B.Cu" "B.Mask" "B.Paste")
			(net "GND")
		)
	)
	(footprint ""
		(layer "B.Cu")
		(at 147.305014 -73.683622 180)
		(property "Reference" "C347"
			(at -4.93522 0.710184 0)
			(unlocked yes)
			(layer "B.SilkS")
			(effects
				(font
					(size 0.7874 0.5842)
					(thickness 0.1524)
				)
				(justify left mirror)
			)
		)
		(property "Value" ""
			(at 0 0 0)
			(layer "B.Fab")
			(effects
				(font
					(size 1.27 1.27)
				)
				(justify mirror)
			)
		)
		(duplicate_pad_numbers_are_jumpers no)
		(fp_line
			(start 0.7874 0.4064)
			(end 0.7874 -0.4064)
			(stroke
				(width 0.1524)
				(type default)
			)
			(layer "B.SilkS")
		)
		(fp_line
			(start 0.7874 -0.4064)
			(end -0.7874 -0.4064)
			(stroke
				(width 0.1524)
				(type default)
			)
			(layer "B.SilkS")
		)
		(fp_line
			(start 0 0.381)
			(end 0 -0.381)
			(stroke
				(width 0.1524)
				(type default)
			)
			(layer "B.SilkS")
		)
		(fp_line
			(start -0.7874 0.4064)
			(end 0.7874 0.4064)
			(stroke
				(width 0.1524)
				(type default)
			)
			(layer "B.SilkS")
		)
		(fp_line
			(start -0.7874 -0.4064)
			(end -0.7874 0.4064)
			(stroke
				(width 0.1524)
				(type default)
			)
			(layer "B.SilkS")
		)
		(fp_poly
			(pts
				(xy 0.5334 0.254) (xy 0.635 0.254) (xy 0.635 0.2286) (xy 0.635 -0.254) (xy 0.5334 -0.254) (xy 0.5334 -0.2794)
				(xy -0.5334 -0.2794) (xy -0.5334 -0.254) (xy -0.635 -0.254) (xy -0.635 0.254) (xy -0.5334 0.254)
				(xy -0.5334 0.2794) (xy 0.508 0.2794) (xy 0.5334 0.2794)
			)
			(stroke
				(width 0)
				(type default)
			)
			(fill no)
			(layer "B.CrtYd")
		)
		(pad "1" smd rect
			(at -0.40005 0)
			(size 0.4572 0.508)
			(layers "B.Cu" "B.Mask" "B.Paste")
			(net "P1V8_SATA_AVDD_NODE1")
		)
		(pad "2" smd rect
			(at 0.40005 0)
			(size 0.4572 0.508)
			(layers "B.Cu" "B.Mask" "B.Paste")
			(net "GND")
		)
	)
	(footprint ""
		(layer "B.Cu")
		(at 79.55026 -86.557612 90)
		(property "Reference" "C33"
			(at 1.103884 -0.01397 270)
			(unlocked yes)
			(layer "B.SilkS")
			(effects
				(font
					(size 0.7874 0.5842)
					(thickness 0.1524)
				)
				(justify left mirror)
			)
		)
		(property "Value" ""
			(at 0 0 90)
			(layer "B.Fab")
			(effects
				(font
					(size 1.27 1.27)
				)
				(justify mirror)
			)
		)
		(duplicate_pad_numbers_are_jumpers no)
		(fp_line
			(start 0.7874 -0.4064)
			(end -0.7874 -0.4064)
			(stroke
				(width 0.1524)
				(type default)
			)
			(layer "B.SilkS")
		)
		(fp_line
			(start -0.7874 -0.4064)
			(end -0.7874 0.4064)
			(stroke
				(width 0.1524)
				(type default)
			)
			(layer "B.SilkS")
		)
		(fp_line
			(start 0 0.381)
			(end 0 -0.381)
			(stroke
				(width 0.1524)
				(type default)
			)
			(layer "B.SilkS")
		)
		(fp_line
			(start 0.7874 0.4064)
			(end 0.7874 -0.4064)
			(stroke
				(width 0.1524)
				(type default)
			)
			(layer "B.SilkS")
		)
		(fp_line
			(start -0.7874 0.4064)
			(end 0.7874 0.4064)
			(stroke
				(width 0.1524)
				(type default)
			)
			(layer "B.SilkS")
		)
		(fp_poly
			(pts
				(xy 0.5334 0.254) (xy 0.635 0.254) (xy 0.635 0.2286) (xy 0.635 -0.254) (xy 0.5334 -0.254) (xy 0.5334 -0.2794)
				(xy -0.5334 -0.2794) (xy -0.5334 -0.254) (xy -0.635 -0.254) (xy -0.635 0.254) (xy -0.5334 0.254)
				(xy -0.5334 0.2794) (xy 0.508 0.2794) (xy 0.5334 0.2794)
			)
			(stroke
				(width 0)
				(type default)
			)
			(fill no)
			(layer "B.CrtYd")
		)
		(pad "1" smd rect
			(at -0.40005 0 270)
			(size 0.4572 0.508)
			(layers "B.Cu" "B.Mask" "B.Paste")
			(net "P3V3_RTC_NODE1")
		)
		(pad "2" smd rect
			(at 0.40005 0 270)
			(size 0.4572 0.508)
			(layers "B.Cu" "B.Mask" "B.Paste")
			(net "GND")
		)
	)
)
